(kicad_pcb
	(version 20260206)
	(generator "pcbnew")
	(generator_version "10.0")
	(general
		(thickness 1.6)
		(legacy_teardrops no)
	)
	(paper "A4")
	(title_block
		(title "01162023_DA0F0TEBIF0_F0T_Expander_BD_F_brd_V02_OCP.brd")
		(comment 1 "Grand Teton / footprints 8879-8885 of 9728")
	)
	(layers
		(0 "F.Cu" signal "TOP")
		(4 "In1.Cu" signal "GND")
		(6 "In2.Cu" signal "VCC")
		(8 "In3.Cu" signal "VCC1")
		(10 "In4.Cu" signal "GND1")
		(12 "In5.Cu" signal "IN1")
		(14 "In6.Cu" signal "GND2")
		(16 "In7.Cu" signal "IN2")
		(18 "In8.Cu" signal "GND3")
		(20 "In9.Cu" signal "IN3")
		(22 "In10.Cu" signal "GND4")
		(24 "In11.Cu" signal "IN4")
		(26 "In12.Cu" signal "GND5")
		(28 "In13.Cu" signal "IN5")
		(30 "In14.Cu" signal "GND6")
		(32 "In15.Cu" signal "IN6")
		(34 "In16.Cu" signal "GND7")
		(2 "B.Cu" signal "BOTTOM")
		(9 "F.Adhes" user "F.Adhesive")
		(11 "B.Adhes" user "B.Adhesive")
		(13 "F.Paste" user "Package Geometry/Pastemask Top")
		(15 "B.Paste" user "Package Geometry/Pastemask Bottom")
		(5 "F.SilkS" user "Ref Des/Silkscreen Top")
		(7 "B.SilkS" user "Ref Des/Silkscreen Bottom")
		(1 "F.Mask" user "Board Geometry/Soldermask Top")
		(3 "B.Mask" user "Board Geometry/Soldermask Bottom")
		(17 "Dwgs.User" user "User.Drawings")
		(19 "Cmts.User" user "User.Comments")
		(21 "Eco1.User" user "User.Eco1")
		(23 "Eco2.User" user "User.Eco2")
		(25 "Edge.Cuts" user "Board Geometry/Outline")
		(27 "Margin" user)
		(31 "F.CrtYd" user "Package Geometry/Place Bound Top")
		(29 "B.CrtYd" user "Package Geometry/Place Bound Bottom")
		(35 "F.Fab" user "Ref Des/Assembly Top")
		(33 "B.Fab" user "Ref Des/Assembly Bottom")
	)
	(footprint ""
		(layer "B.Cu")
		(at 288.46272 -197.910196)
		(property "Reference" "Q241"
			(at 1.651 -2.25933 0)
			(unlocked yes)
			(layer "B.SilkS")
			(effects
				(font
					(size 0.7874 0.5842)
					(thickness 0.1524)
				)
				(justify left mirror)
			)
		)
		(property "Value" ""
			(at 0 0 0)
			(layer "B.Fab")
			(effects
				(font
					(size 1.27 1.27)
				)
				(justify mirror)
			)
		)
		(duplicate_pad_numbers_are_jumpers no)
		(fp_line
			(start -1.603248 -1.500124)
			(end -1.603248 1.500124)
			(stroke
				(width 0.1524)
				(type default)
			)
			(layer "B.SilkS")
		)
		(fp_line
			(start -1.603248 1.500124)
			(end 1.603248 1.500124)
			(stroke
				(width 0.1524)
				(type default)
			)
			(layer "B.SilkS")
		)
		(fp_line
			(start 1.603248 -1.500124)
			(end -1.603248 -1.500124)
			(stroke
				(width 0.1524)
				(type default)
			)
			(layer "B.SilkS")
		)
		(fp_line
			(start 1.603248 1.500124)
			(end 1.603248 -1.500124)
			(stroke
				(width 0.1524)
				(type default)
			)
			(layer "B.SilkS")
		)
		(fp_line
			(start -1.249934 -0.219964)
			(end -0.700024 -0.219964)
			(stroke
				(width 0.1)
				(type default)
			)
			(layer "B.Fab")
		)
		(fp_line
			(start -1.249934 0.219964)
			(end -1.249934 -0.219964)
			(stroke
				(width 0.1)
				(type default)
			)
			(layer "B.Fab")
		)
		(fp_line
			(start -0.700024 -1.500124)
			(end 0.700024 -1.500124)
			(stroke
				(width 0.1)
				(type default)
			)
			(layer "B.Fab")
		)
		(fp_line
			(start -0.700024 -0.219964)
			(end -0.700024 -1.500124)
			(stroke
				(width 0.1)
				(type default)
			)
			(layer "B.Fab")
		)
		(fp_line
			(start -0.700024 0.219964)
			(end -1.249934 0.219964)
			(stroke
				(width 0.1)
				(type default)
			)
			(layer "B.Fab")
		)
		(fp_line
			(start -0.700024 1.500124)
			(end -0.700024 0.219964)
			(stroke
				(width 0.1)
				(type default)
			)
			(layer "B.Fab")
		)
		(fp_line
			(start 0.6985 -0.729996)
			(end 0.6985 0.729996)
			(stroke
				(width 0.1)
				(type default)
			)
			(layer "B.Fab")
		)
		(fp_line
			(start 0.6985 0.729996)
			(end 1.249934 0.729996)
			(stroke
				(width 0.1)
				(type default)
			)
			(layer "B.Fab")
		)
		(fp_line
			(start 0.700024 -1.500124)
			(end 0.700024 -1.169924)
			(stroke
				(width 0.1)
				(type default)
			)
			(layer "B.Fab")
		)
		(fp_line
			(start 0.700024 -1.169924)
			(end 1.249934 -1.169924)
			(stroke
				(width 0.1)
				(type default)
			)
			(layer "B.Fab")
		)
		(fp_line
			(start 0.700024 1.169924)
			(end 0.700024 1.500124)
			(stroke
				(width 0.1)
				(type default)
			)
			(layer "B.Fab")
		)
		(fp_line
			(start 0.700024 1.500124)
			(end -0.700024 1.500124)
			(stroke
				(width 0.1)
				(type default)
			)
			(layer "B.Fab")
		)
		(fp_line
			(start 1.249934 -1.169924)
			(end 1.249934 -0.729996)
			(stroke
				(width 0.1)
				(type default)
			)
			(layer "B.Fab")
		)
		(fp_line
			(start 1.249934 -0.729996)
			(end 0.6985 -0.729996)
			(stroke
				(width 0.1)
				(type default)
			)
			(layer "B.Fab")
		)
		(fp_line
			(start 1.249934 0.729996)
			(end 1.249934 1.169924)
			(stroke
				(width 0.1)
				(type default)
			)
			(layer "B.Fab")
		)
		(fp_line
			(start 1.249934 1.169924)
			(end 0.700024 1.169924)
			(stroke
				(width 0.1)
				(type default)
			)
			(layer "B.Fab")
		)
		(fp_rect
			(start 0.700024 1.500124)
			(end -0.700024 -1.500124)
			(stroke
				(width 0)
				(type default)
			)
			(fill no)
			(layer "B.Fab")
		)
		(pad "D" smd rect
			(at -0.999998 0 270)
			(size 0.8128 0.9144)
			(layers "B.Cu" "B.Mask" "B.Paste")
			(net "SPI_BIC1_LS23_EN_N")
		)
		(pad "G" smd rect
			(at 0.999998 -0.94996 270)
			(size 0.8128 0.9144)
			(layers "B.Cu" "B.Mask" "B.Paste")
			(net "SPI_BIC1_LS23_EN")
		)
		(pad "S" smd rect
			(at 0.999998 0.94996 270)
			(size 0.8128 0.9144)
			(layers "B.Cu" "B.Mask" "B.Paste")
			(net "GND")
		)
	)
	(footprint ""
		(layer "B.Cu")
		(at 208.279238 -227.04679)
		(property "Reference" "R6822"
			(at 0 0 0)
			(layer "B.SilkS")
			(hide yes)
			(effects
				(font
					(size 1.27 1.27)
				)
				(justify mirror)
			)
		)
		(property "Value" ""
			(at 0 0 0)
			(layer "B.Fab")
			(effects
				(font
					(size 1.27 1.27)
				)
				(justify mirror)
			)
		)
		(duplicate_pad_numbers_are_jumpers no)
		(fp_line
			(start -0.7874 -0.4064)
			(end -0.7874 0.4064)
			(stroke
				(width 0.1524)
				(type default)
			)
			(layer "B.SilkS")
		)
		(fp_line
			(start -0.7874 0.4064)
			(end 0.7874 0.4064)
			(stroke
				(width 0.1524)
				(type default)
			)
			(layer "B.SilkS")
		)
		(fp_line
			(start 0.7874 -0.4064)
			(end -0.7874 -0.4064)
			(stroke
				(width 0.1524)
				(type default)
			)
			(layer "B.SilkS")
		)
		(fp_line
			(start 0.7874 0.4064)
			(end 0.7874 -0.4064)
			(stroke
				(width 0.1524)
				(type default)
			)
			(layer "B.SilkS")
		)
		(fp_line
			(start -0.67945 -0.3048)
			(end -0.67945 0.3048)
			(stroke
				(width 0.1)
				(type default)
			)
			(layer "B.Fab")
		)
		(fp_line
			(start -0.67945 0.3048)
			(end -0.120396 0.3048)
			(stroke
				(width 0.1)
				(type default)
			)
			(layer "B.Fab")
		)
		(fp_line
			(start -0.12065 -0.3048)
			(end -0.67945 -0.3048)
			(stroke
				(width 0.1)
				(type default)
			)
			(layer "B.Fab")
		)
		(fp_line
			(start -0.12065 -0.2794)
			(end -0.12065 -0.3048)
			(stroke
				(width 0.1)
				(type default)
			)
			(layer "B.Fab")
		)
		(fp_line
			(start -0.120396 0.2794)
			(end 0.12065 0.2794)
			(stroke
				(width 0.1)
				(type default)
			)
			(layer "B.Fab")
		)
		(fp_line
			(start -0.120396 0.3048)
			(end -0.120396 0.2794)
			(stroke
				(width 0.1)
				(type default)
			)
			(layer "B.Fab")
		)
		(fp_line
			(start 0.12065 -0.305054)
			(end 0.12065 -0.2794)
			(stroke
				(width 0.1)
				(type default)
			)
			(layer "B.Fab")
		)
		(fp_line
			(start 0.12065 -0.2794)
			(end -0.12065 -0.2794)
			(stroke
				(width 0.1)
				(type default)
			)
			(layer "B.Fab")
		)
		(fp_line
			(start 0.12065 0.2794)
			(end 0.12065 0.3048)
			(stroke
				(width 0.1)
				(type default)
			)
			(layer "B.Fab")
		)
		(fp_line
			(start 0.12065 0.3048)
			(end 0.67945 0.3048)
			(stroke
				(width 0.1)
				(type default)
			)
			(layer "B.Fab")
		)
		(fp_line
			(start 0.67945 -0.305054)
			(end 0.12065 -0.305054)
			(stroke
				(width 0.1)
				(type default)
			)
			(layer "B.Fab")
		)
		(fp_line
			(start 0.67945 0.3048)
			(end 0.67945 -0.305054)
			(stroke
				(width 0.1)
				(type default)
			)
			(layer "B.Fab")
		)
		(pad "1" smd circle
			(at 0.40005 0 180)
			(size 0 0)
			(layers "B.Cu" "B.Mask" "B.Paste")
			(net "ADC_TYPE_ADC_R")
		)
		(pad "2" smd circle
			(at -0.40005 0 180)
			(size 0 0)
			(layers "B.Cu" "B.Mask" "B.Paste")
			(net "P3V3_AUX")
		)
	)
	(footprint ""
		(layer "B.Cu")
		(at 112.73536 -308.580028 90)
		(property "Reference" "C4198"
			(at 0 0 90)
			(layer "B.SilkS")
			(hide yes)
			(effects
				(font
					(size 1.27 1.27)
				)
				(justify mirror)
			)
		)
		(property "Value" ""
			(at 0 0 90)
			(layer "B.Fab")
			(effects
				(font
					(size 1.27 1.27)
				)
				(justify mirror)
			)
		)
		(duplicate_pad_numbers_are_jumpers no)
		(fp_line
			(start 1.2954 -0.5842)
			(end -1.2954 -0.5842)
			(stroke
				(width 0.1524)
				(type default)
			)
			(layer "B.SilkS")
		)
		(fp_line
			(start -1.2954 -0.5842)
			(end -1.2954 0.5842)
			(stroke
				(width 0.1524)
				(type default)
			)
			(layer "B.SilkS")
		)
		(fp_line
			(start 1.2954 0.5842)
			(end 1.2954 -0.5842)
			(stroke
				(width 0.1524)
				(type default)
			)
			(layer "B.SilkS")
		)
		(fp_line
			(start -1.2954 0.5842)
			(end 1.2954 0.5842)
			(stroke
				(width 0.1524)
				(type default)
			)
			(layer "B.SilkS")
		)
		(fp_line
			(start 0.8636 -0.4572)
			(end -0.8636 -0.4572)
			(stroke
				(width 0.1)
				(type default)
			)
			(layer "B.Fab")
		)
		(fp_line
			(start -0.8636 -0.4572)
			(end -0.8636 -0.4064)
			(stroke
				(width 0.1)
				(type default)
			)
			(layer "B.Fab")
		)
		(fp_line
			(start 1.1938 -0.4064)
			(end 0.8636 -0.4064)
			(stroke
				(width 0.1)
				(type default)
			)
			(layer "B.Fab")
		)
		(fp_line
			(start 0.8636 -0.4064)
			(end 0.8636 -0.4572)
			(stroke
				(width 0.1)
				(type default)
			)
			(layer "B.Fab")
		)
		(fp_line
			(start -0.8636 -0.4064)
			(end -1.1938 -0.4064)
			(stroke
				(width 0.1)
				(type default)
			)
			(layer "B.Fab")
		)
		(fp_line
			(start -1.1938 -0.4064)
			(end -1.1938 0.4064)
			(stroke
				(width 0.1)
				(type default)
			)
			(layer "B.Fab")
		)
		(fp_line
			(start 1.1938 0.4064)
			(end 1.1938 -0.4064)
			(stroke
				(width 0.1)
				(type default)
			)
			(layer "B.Fab")
		)
		(fp_line
			(start 0.8636 0.4064)
			(end 1.1938 0.4064)
			(stroke
				(width 0.1)
				(type default)
			)
			(layer "B.Fab")
		)
		(fp_line
			(start -0.8636 0.4064)
			(end -0.8636 0.4572)
			(stroke
				(width 0.1)
				(type default)
			)
			(layer "B.Fab")
		)
		(fp_line
			(start -1.1938 0.4064)
			(end -0.8636 0.4064)
			(stroke
				(width 0.1)
				(type default)
			)
			(layer "B.Fab")
		)
		(fp_line
			(start 0.8636 0.4572)
			(end 0.8636 0.4064)
			(stroke
				(width 0.1)
				(type default)
			)
			(layer "B.Fab")
		)
		(fp_line
			(start -0.8636 0.4572)
			(end 0.8636 0.4572)
			(stroke
				(width 0.1)
				(type default)
			)
			(layer "B.Fab")
		)
		(pad "1" smd rect
			(at 0.7366 0)
			(size 0.7112 0.8128)
			(layers "B.Cu" "B.Mask" "B.Paste")
			(net "P0V8_PEX0")
		)
		(pad "2" smd rect
			(at -0.7366 0)
			(size 0.7112 0.8128)
			(layers "B.Cu" "B.Mask" "B.Paste")
			(net "GND")
		)
	)
	(footprint ""
		(layer "B.Cu")
		(at 353.277424 -281.024838 90)
		(property "Reference" "PC174"
			(at 0 0 90)
			(layer "B.SilkS")
			(hide yes)
			(effects
				(font
					(size 1.27 1.27)
				)
				(justify mirror)
			)
		)
		(property "Value" ""
			(at 0 0 90)
			(layer "B.Fab")
			(effects
				(font
					(size 1.27 1.27)
				)
				(justify mirror)
			)
		)
		(duplicate_pad_numbers_are_jumpers no)
		(fp_line
			(start 1.524 -0.762)
			(end -1.524 -0.762)
			(stroke
				(width 0.1524)
				(type default)
			)
			(layer "B.SilkS")
		)
		(fp_line
			(start -1.524 -0.762)
			(end -1.524 0.762)
			(stroke
				(width 0.1524)
				(type default)
			)
			(layer "B.SilkS")
		)
		(fp_line
			(start 1.524 0.762)
			(end 1.524 -0.762)
			(stroke
				(width 0.1524)
				(type default)
			)
			(layer "B.SilkS")
		)
		(fp_line
			(start -1.524 0.762)
			(end 1.524 0.762)
			(stroke
				(width 0.1524)
				(type default)
			)
			(layer "B.SilkS")
		)
		(fp_line
			(start 1.1049 -0.724916)
			(end 1.1049 0.724916)
			(stroke
				(width 0.1)
				(type default)
			)
			(layer "B.Fab")
		)
		(fp_line
			(start -1.1049 -0.724916)
			(end 1.1049 -0.724916)
			(stroke
				(width 0.1)
				(type default)
			)
			(layer "B.Fab")
		)
		(fp_line
			(start 1.1049 0.724916)
			(end -1.1049 0.724916)
			(stroke
				(width 0.1)
				(type default)
			)
			(layer "B.Fab")
		)
		(fp_line
			(start -1.1049 0.724916)
			(end -1.1049 -0.724916)
			(stroke
				(width 0.1)
				(type default)
			)
			(layer "B.Fab")
		)
		(pad "1" smd rect
			(at 0.889 0 90)
			(size 1.016 1.27)
			(layers "B.Cu" "B.Mask" "B.Paste")
			(net "SW_P12V_P0V8_PEX3_FLT")
		)
		(pad "2" smd rect
			(at -0.889 0 90)
			(size 1.016 1.27)
			(layers "B.Cu" "B.Mask" "B.Paste")
			(net "GND")
		)
	)
	(footprint ""
		(layer "B.Cu")
		(at 72.949816 -295.89984 180)
		(property "Reference" "C2977"
			(at 0 0 0)
			(layer "B.SilkS")
			(hide yes)
			(effects
				(font
					(size 1.27 1.27)
				)
				(justify mirror)
			)
		)
		(property "Value" ""
			(at 0 0 0)
			(layer "B.Fab")
			(effects
				(font
					(size 1.27 1.27)
				)
				(justify mirror)
			)
		)
		(duplicate_pad_numbers_are_jumpers no)
		(fp_line
			(start 0.299974 0.150114)
			(end 0.299974 -0.150114)
			(stroke
				(width 0.1)
				(type default)
			)
			(layer "B.Fab")
		)
		(fp_line
			(start 0.299974 -0.150114)
			(end -0.299974 -0.150114)
			(stroke
				(width 0.1)
				(type default)
			)
			(layer "B.Fab")
		)
		(fp_line
			(start -0.299974 0.150114)
			(end 0.299974 0.150114)
			(stroke
				(width 0.1)
				(type default)
			)
			(layer "B.Fab")
		)
		(fp_line
			(start -0.299974 -0.150114)
			(end -0.299974 0.150114)
			(stroke
				(width 0.1)
				(type default)
			)
			(layer "B.Fab")
		)
		(pad "1" smd rect
			(at 0.2667 0)
			(size 0.3048 0.381)
			(layers "B.Cu" "B.Mask" "B.Paste")
			(net "P1V25_SERDES_VDDPLL_PEX0")
		)
		(pad "2" smd rect
			(at -0.2667 0)
			(size 0.3048 0.381)
			(layers "B.Cu" "B.Mask" "B.Paste")
			(net "GND")
		)
	)
	(footprint ""
		(layer "B.Cu")
		(at 55.849774 -290.199826 90)
		(property "Reference" "C1215"
			(at 0 0 90)
			(layer "B.SilkS")
			(hide yes)
			(effects
				(font
					(size 1.27 1.27)
				)
				(justify mirror)
			)
		)
		(property "Value" ""
			(at 0 0 90)
			(layer "B.Fab")
			(effects
				(font
					(size 1.27 1.27)
				)
				(justify mirror)
			)
		)
		(duplicate_pad_numbers_are_jumpers no)
		(fp_line
			(start 0.299974 -0.150114)
			(end -0.299974 -0.150114)
			(stroke
				(width 0.1)
				(type default)
			)
			(layer "B.Fab")
		)
		(fp_line
			(start -0.299974 -0.150114)
			(end -0.299974 0.150114)
			(stroke
				(width 0.1)
				(type default)
			)
			(layer "B.Fab")
		)
		(fp_line
			(start 0.299974 0.150114)
			(end 0.299974 -0.150114)
			(stroke
				(width 0.1)
				(type default)
			)
			(layer "B.Fab")
		)
		(fp_line
			(start -0.299974 0.150114)
			(end 0.299974 0.150114)
			(stroke
				(width 0.1)
				(type default)
			)
			(layer "B.Fab")
		)
		(pad "1" smd rect
			(at 0.2667 0 270)
			(size 0.3048 0.381)
			(layers "B.Cu" "B.Mask" "B.Paste")
			(net "P0V8_SERDES_VDDA_PEX0")
		)
		(pad "2" smd rect
			(at -0.2667 0 270)
			(size 0.3048 0.381)
			(layers "B.Cu" "B.Mask" "B.Paste")
			(net "GND")
		)
	)
	(footprint ""
		(layer "B.Cu")
		(at 133.175756 -182.347362 180)
		(property "Reference" "C2653"
			(at 0 0 0)
			(layer "B.SilkS")
			(hide yes)
			(effects
				(font
					(size 1.27 1.27)
				)
				(justify mirror)
			)
		)
		(property "Value" ""
			(at 0 0 0)
			(layer "B.Fab")
			(effects
				(font
					(size 1.27 1.27)
				)
				(justify mirror)
			)
		)
		(duplicate_pad_numbers_are_jumpers no)
		(fp_line
			(start 1.2954 0.5842)
			(end 1.2954 -0.5842)
			(stroke
				(width 0.1524)
				(type default)
			)
			(layer "B.SilkS")
		)
		(fp_line
			(start 1.2954 -0.5842)
			(end -1.2954 -0.5842)
			(stroke
				(width 0.1524)
				(type default)
			)
			(layer "B.SilkS")
		)
		(fp_line
			(start -1.2954 0.5842)
			(end 1.2954 0.5842)
			(stroke
				(width 0.1524)
				(type default)
			)
			(layer "B.SilkS")
		)
		(fp_line
			(start -1.2954 -0.5842)
			(end -1.2954 0.5842)
			(stroke
				(width 0.1524)
				(type default)
			)
			(layer "B.SilkS")
		)
		(fp_line
			(start 1.1938 0.4064)
			(end 1.1938 -0.4064)
			(stroke
				(width 0.1)
				(type default)
			)
			(layer "B.Fab")
		)
		(fp_line
			(start 1.1938 -0.4064)
			(end 0.8636 -0.4064)
			(stroke
				(width 0.1)
				(type default)
			)
			(layer "B.Fab")
		)
		(fp_line
			(start 0.8636 0.4572)
			(end 0.8636 0.4064)
			(stroke
				(width 0.1)
				(type default)
			)
			(layer "B.Fab")
		)
		(fp_line
			(start 0.8636 0.4064)
			(end 1.1938 0.4064)
			(stroke
				(width 0.1)
				(type default)
			)
			(layer "B.Fab")
		)
		(fp_line
			(start 0.8636 -0.4064)
			(end 0.8636 -0.4572)
			(stroke
				(width 0.1)
				(type default)
			)
			(layer "B.Fab")
		)
		(fp_line
			(start 0.8636 -0.4572)
			(end -0.8636 -0.4572)
			(stroke
				(width 0.1)
				(type default)
			)
			(layer "B.Fab")
		)
		(fp_line
			(start -0.8636 0.4572)
			(end 0.8636 0.4572)
			(stroke
				(width 0.1)
				(type default)
			)
			(layer "B.Fab")
		)
		(fp_line
			(start -0.8636 0.4064)
			(end -0.8636 0.4572)
			(stroke
				(width 0.1)
				(type default)
			)
			(layer "B.Fab")
		)
		(fp_line
			(start -0.8636 -0.4064)
			(end -1.1938 -0.4064)
			(stroke
				(width 0.1)
				(type default)
			)
			(layer "B.Fab")
		)
		(fp_line
			(start -0.8636 -0.4572)
			(end -0.8636 -0.4064)
			(stroke
				(width 0.1)
				(type default)
			)
			(layer "B.Fab")
		)
		(fp_line
			(start -1.1938 0.4064)
			(end -0.8636 0.4064)
			(stroke
				(width 0.1)
				(type default)
			)
			(layer "B.Fab")
		)
		(fp_line
			(start -1.1938 -0.4064)
			(end -1.1938 0.4064)
			(stroke
				(width 0.1)
				(type default)
			)
			(layer "B.Fab")
		)
		(pad "1" smd rect
			(at 0.7366 0 90)
			(size 0.7112 0.8128)
			(layers "B.Cu" "B.Mask" "B.Paste")
			(net "P3V3_DB2000QL_VDDA")
		)
		(pad "2" smd rect
			(at -0.7366 0 90)
			(size 0.7112 0.8128)
			(layers "B.Cu" "B.Mask" "B.Paste")
			(net "GND")
		)
	)
)
